# BASEBOARD_FAB2 (Tioga Pass) — schematic netlist excerpt (pin names and nets, part order shuffled) for the footprints in the layout excerpt that follows; sources: Cadence DE-HDL packaged netlist, KiCad conversion of Wiwynn_Tioga_Pass_MB.brd

C2D41  CAP_A  22.0UF 4V 20% X6S  pkg 0603V  page 225 : A = PVDDQ_GHJ ; B = GND
C3B2  CAP  10UF 4V 20% X6S  pkg 0603LF  page 234 : A = PVPP_KLM ; B = GND
R1G16  RES  1.00K 1% CHIP  pkg 0402  page 223 : A = P3V3_STBY ; B = PWRGD_PVDDQ_GHJ_R

(kicad_pcb
	(version 20260206)
	(generator "pcbnew")
	(generator_version "10.0")
	(general
		(thickness 1.6)
		(legacy_teardrops no)
	)
	(paper "A4")
	(title_block
		(title "Wiwynn_Tioga_Pass_MB.brd")
		(comment 1 "Tioga Pass / footprints 290-292 of 4770")
	)
	(layers
		(0 "F.Cu" signal "TOP")
		(4 "In1.Cu" signal "L2GND")
		(6 "In2.Cu" signal "L3")
		(8 "In3.Cu" signal "L4GND")
		(10 "In4.Cu" signal "L5")
		(12 "In5.Cu" signal "L6GND")
		(14 "In6.Cu" signal "L7VCC")
		(16 "In7.Cu" signal "L8VCC")
		(18 "In8.Cu" signal "L9GND")
		(20 "In9.Cu" signal "L10")
		(22 "In10.Cu" signal "L11GND")
		(24 "In11.Cu" signal "L12")
		(26 "In12.Cu" signal "L13GND")
		(2 "B.Cu" signal "BOTTOM")
		(9 "F.Adhes" user "F.Adhesive")
		(11 "B.Adhes" user "B.Adhesive")
		(13 "F.Paste" user "Package Geometry/Pastemask Top")
		(15 "B.Paste" user "Package Geometry/Pastemask Bottom")
		(5 "F.SilkS" user "Ref Des/Silkscreen Top")
		(7 "B.SilkS" user "Ref Des/Silkscreen Bottom")
		(1 "F.Mask" user "Board Geometry/Soldermask Top")
		(3 "B.Mask" user "Board Geometry/Soldermask Bottom")
		(17 "Dwgs.User" user "User.Drawings")
		(19 "Cmts.User" user "User.Comments")
		(21 "Eco1.User" user "User.Eco1")
		(23 "Eco2.User" user "User.Eco2")
		(25 "Edge.Cuts" user "Board Geometry/Outline")
		(27 "Margin" user)
		(31 "F.CrtYd" user "Package Geometry/Place Bound Top")
		(29 "B.CrtYd" user "Package Geometry/Place Bound Bottom")
		(35 "F.Fab" user "Ref Des/Assembly Top")
		(33 "B.Fab" user "Ref Des/Assembly Bottom")
	)
	(footprint ""
		(layer "F.Cu")
		(at 99.453192 -69.885814 -90)
		(property "Reference" "C2D41"
			(at 0 0 270)
			(layer "F.SilkS")
			(hide yes)
			(effects
				(font
					(size 1.27 1.27)
				)
			)
		)
		(property "Value" ""
			(at 0 0 270)
			(layer "F.Fab")
			(effects
				(font
					(size 1.27 1.27)
				)
			)
		)
		(duplicate_pad_numbers_are_jumpers no)
		(fp_poly
			(pts
				(xy -0.4953 -0.2032) (xy 0.4953 -0.2032) (xy 0.4953 1.6002) (xy -0.4953 1.6002)
			)
			(stroke
				(width 0)
				(type default)
			)
			(fill no)
			(layer "F.CrtYd")
		)
		(fp_line
			(start -0.4953 1.6002)
			(end -0.4953 -0.2032)
			(stroke
				(width 0.1)
				(type default)
			)
			(layer "F.Fab")
		)
		(fp_line
			(start 0.4953 1.6002)
			(end -0.4953 1.6002)
			(stroke
				(width 0.1)
				(type default)
			)
			(layer "F.Fab")
		)
		(fp_line
			(start -0.4953 -0.2032)
			(end 0.4953 -0.2032)
			(stroke
				(width 0.1)
				(type default)
			)
			(layer "F.Fab")
		)
		(fp_line
			(start 0.4953 -0.2032)
			(end 0.4953 1.6002)
			(stroke
				(width 0.1)
				(type default)
			)
			(layer "F.Fab")
		)
		(pad "1" smd rect
			(at 0 0 270)
			(size 0.762 0.889)
			(layers "F.Cu" "F.Mask" "F.Paste")
			(net "PVDDQ_GHJ")
		)
		(pad "2" smd rect
			(at 0 1.397 270)
			(size 0.762 0.889)
			(layers "F.Cu" "F.Mask" "F.Paste")
			(net "GND")
		)
		(zone
			(layer "F.Cu")
			(hatch none 0.5)
			(connect_pads
				(clearance 0)
			)
			(min_thickness 0.25)
			(keepout
				(tracks not_allowed)
				(vias allowed)
				(pads allowed)
				(copperpour not_allowed)
				(footprints allowed)
			)
			(placement
				(enabled no)
				(sheetname "")
			)
			(fill
				(thermal_gap 0.5)
				(thermal_bridge_width 0.5)
				(island_removal_mode 0)
			)
			(polygon
				(pts
					(xy 99.008692 -70.266814) (xy 99.008692 -69.504814) (xy 98.500692 -69.504814) (xy 98.500692 -70.266814)
				)
			)
		)
	)
	(footprint ""
		(layer "F.Cu")
		(at 155.0416 -130.3528 90)
		(property "Reference" "C3B2"
			(at 0 0 90)
			(layer "F.SilkS")
			(hide yes)
			(effects
				(font
					(size 1.27 1.27)
				)
			)
		)
		(property "Value" ""
			(at 0 0 90)
			(layer "F.Fab")
			(effects
				(font
					(size 1.27 1.27)
				)
			)
		)
		(duplicate_pad_numbers_are_jumpers no)
		(fp_rect
			(start -0.4953 1.6002)
			(end 0.4953 -0.2032)
			(stroke
				(width 0)
				(type default)
			)
			(fill no)
			(layer "F.CrtYd")
		)
		(fp_line
			(start 0.4953 -0.2032)
			(end 0.4953 1.6002)
			(stroke
				(width 0.1)
				(type default)
			)
			(layer "F.Fab")
		)
		(fp_line
			(start -0.4953 -0.2032)
			(end 0.4953 -0.2032)
			(stroke
				(width 0.1)
				(type default)
			)
			(layer "F.Fab")
		)
		(fp_line
			(start 0.4953 1.6002)
			(end -0.4953 1.6002)
			(stroke
				(width 0.1)
				(type default)
			)
			(layer "F.Fab")
		)
		(fp_line
			(start -0.4953 1.6002)
			(end -0.4953 -0.2032)
			(stroke
				(width 0.1)
				(type default)
			)
			(layer "F.Fab")
		)
		(pad "1" smd rect
			(at 0 0 90)
			(size 0.762 0.889)
			(layers "F.Cu" "F.Mask" "F.Paste")
			(net "PVPP_KLM")
		)
		(pad "2" smd rect
			(at 0 1.397 90)
			(size 0.762 0.889)
			(layers "F.Cu" "F.Mask" "F.Paste")
			(net "GND")
		)
		(zone
			(layer "F.Cu")
			(hatch none 0.5)
			(connect_pads
				(clearance 0)
			)
			(min_thickness 0.25)
			(keepout
				(tracks not_allowed)
				(vias allowed)
				(pads allowed)
				(copperpour not_allowed)
				(footprints allowed)
			)
			(placement
				(enabled no)
				(sheetname "")
			)
			(fill
				(thermal_gap 0.5)
				(thermal_bridge_width 0.5)
				(island_removal_mode 0)
			)
			(polygon
				(pts
					(xy 155.9941 -129.9718) (xy 155.9941 -130.7338) (xy 155.4861 -130.7338) (xy 155.4861 -129.9718)
				)
			)
		)
	)
	(footprint ""
		(layer "F.Cu")
		(at 14.529816 -2.086864 -90)
		(property "Reference" "R1G16"
			(at 0 0 270)
			(layer "F.SilkS")
			(hide yes)
			(effects
				(font
					(size 1.27 1.27)
				)
			)
		)
		(property "Value" ""
			(at 0 0 270)
			(layer "F.Fab")
			(effects
				(font
					(size 1.27 1.27)
				)
			)
		)
		(duplicate_pad_numbers_are_jumpers no)
		(fp_rect
			(start -0.2794 0.9906)
			(end 0.2794 -0.1016)
			(stroke
				(width 0)
				(type default)
			)
			(fill no)
			(layer "F.CrtYd")
		)
		(fp_line
			(start -0.2794 0.9906)
			(end 0.2794 0.9906)
			(stroke
				(width 0.1)
				(type default)
			)
			(layer "F.Fab")
		)
		(fp_line
			(start 0.2794 0.9906)
			(end 0.2794 -0.1016)
			(stroke
				(width 0.1)
				(type default)
			)
			(layer "F.Fab")
		)
		(fp_line
			(start -0.2794 -0.1016)
			(end -0.2794 0.9906)
			(stroke
				(width 0.1)
				(type default)
			)
			(layer "F.Fab")
		)
		(fp_line
			(start 0.2794 -0.1016)
			(end -0.2794 -0.1016)
			(stroke
				(width 0.1)
				(type default)
			)
			(layer "F.Fab")
		)
		(pad "1" smd rect
			(at 0 0 270)
			(size 0.508 0.508)
			(layers "F.Cu" "F.Mask" "F.Paste")
			(net "P3V3_STBY")
		)
		(pad "2" smd rect
			(at 0 0.889 270)
			(size 0.508 0.508)
			(layers "F.Cu" "F.Mask" "F.Paste")
			(net "PWRGD_PVDDQ_GHJ_R")
		)
		(zone
			(layer "F.Cu")
			(hatch none 0.5)
			(connect_pads
				(clearance 0)
			)
			(min_thickness 0.25)
			(keepout
				(tracks allowed)
				(vias not_allowed)
				(pads allowed)
				(copperpour not_allowed)
				(footprints allowed)
			)
			(placement
				(enabled no)
				(sheetname "")
			)
			(fill
				(thermal_gap 0.5)
				(thermal_bridge_width 0.5)
				(island_removal_mode 0)
			)
			(polygon
				(pts
					(xy 13.894816 -2.340864) (xy 13.894816 -1.832864) (xy 14.275816 -1.832864) (xy 14.275816 -2.340864)
				)
			)
		)
		(zone
			(layer "F.Cu")
			(hatch none 0.5)
			(connect_pads
				(clearance 0)
			)
			(min_thickness 0.25)
			(keepout
				(tracks not_allowed)
				(vias allowed)
				(pads allowed)
				(copperpour not_allowed)
				(footprints allowed)
			)
			(placement
				(enabled no)
				(sheetname "")
			)
			(fill
				(thermal_gap 0.5)
				(thermal_bridge_width 0.5)
				(island_removal_mode 0)
			)
			(polygon
				(pts
					(xy 13.894816 -2.340864) (xy 13.894816 -1.832864) (xy 14.275816 -1.832864) (xy 14.275816 -2.340864)
				)
			)
		)
	)
)
